(kicad_pcb
	(version 20260206)
	(generator "pcbnew")
	(generator_version "10.0")
	(general
		(thickness 1.6)
		(legacy_teardrops no)
	)
	(paper "A4")
	(title_block
		(title "Bryce Canyon_IOM_M2_16342-2_OCP.brd")
		(comment 1 "Bryce Canyon / footprint 242 of 1146 (MEZZ1), pads 1-117 of 122")
	)
	(layers
		(0 "F.Cu" signal "TOP")
		(4 "In1.Cu" signal "L2GND")
		(6 "In2.Cu" signal "L3")
		(8 "In3.Cu" signal "L4VCC")
		(10 "In4.Cu" signal "L5VCC")
		(12 "In5.Cu" signal "L6")
		(14 "In6.Cu" signal "L7GND")
		(2 "B.Cu" signal "BOTTOM")
		(9 "F.Adhes" user "F.Adhesive")
		(11 "B.Adhes" user "B.Adhesive")
		(13 "F.Paste" user "Package Geometry/Pastemask Top")
		(15 "B.Paste" user "Package Geometry/Pastemask Bottom")
		(5 "F.SilkS" user "Ref Des/Silkscreen Top")
		(7 "B.SilkS" user "Ref Des/Silkscreen Bottom")
		(1 "F.Mask" user "Board Geometry/Soldermask Top")
		(3 "B.Mask" user "Board Geometry/Soldermask Bottom")
		(17 "Dwgs.User" user "User.Drawings")
		(19 "Cmts.User" user "User.Comments")
		(21 "Eco1.User" user "User.Eco1")
		(23 "Eco2.User" user "User.Eco2")
		(25 "Edge.Cuts" user "Board Geometry/Outline")
		(27 "Margin" user)
		(31 "F.CrtYd" user "Package Geometry/Place Bound Top")
		(29 "B.CrtYd" user "Package Geometry/Place Bound Bottom")
		(35 "F.Fab" user "Ref Des/Assembly Top")
		(33 "B.Fab" user "Ref Des/Assembly Bottom")
	)
	(footprint ""
		(layer "F.Cu")
		(at 77.700124 -72.55002 -90)
		(property "Reference" "MEZZ1"
			(at 0 0 270)
			(layer "F.SilkS")
			(hide yes)
			(effects
				(font
					(size 1.27 1.27)
				)
			)
		)
		(property "Value" "FCI-CONN120-GP-U1"
			(at -28.2321 -1.7018 270)
			(unlocked yes)
			(layer "F.Fab")
			(hide yes)
			(effects
				(font
					(size 1.016 1.016)
					(thickness 0.1524)
				)
			)
		)
		(property "Device Type" "61082-121402LF-U1"
			(at -28.2321 -3.2258 270)
			(unlocked yes)
			(layer "F.Fab")
			(hide yes)
			(effects
				(font
					(size 1.016 1.016)
					(thickness 0.1524)
				)
			)
		)
		(duplicate_pad_numbers_are_jumpers no)
		(pad "" np_thru_hole circle
			(at -26.100024 0 270)
			(size 0.254 0.254)
			(drill 0.8636)
			(layers "*.Cu" "*.Mask")
			(clearance 0.6604)
			(thermal_gap 0.6604)
		)
		(pad "" np_thru_hole circle
			(at 26.100024 0 270)
			(size 0.254 0.254)
			(drill 1.2192)
			(layers "*.Cu" "*.Mask")
			(clearance 0.8382)
			(thermal_gap 0.8382)
		)
		(pad "1" smd rect
			(at 23.599902 -2.22504 270)
			(size 0.508 2.0574)
			(layers "F.Cu" "F.Mask" "F.Paste")
			(net "MEZZA_PRSNT1_N")
		)
		(pad "2" smd rect
			(at 22.800056 -2.22504 270)
			(size 0.508 2.0574)
			(layers "F.Cu" "F.Mask" "F.Paste")
			(net "P5V_STBY")
		)
		(pad "3" smd rect
			(at 21.999956 -2.22504 270)
			(size 0.508 2.0574)
			(layers "F.Cu" "F.Mask" "F.Paste")
			(net "P5V_STBY")
		)
		(pad "4" smd rect
			(at 21.20011 -2.22504 270)
			(size 0.508 2.0574)
			(layers "F.Cu" "F.Mask" "F.Paste")
			(net "P5V_STBY")
		)
		(pad "5" smd rect
			(at 20.40001 -2.22504 270)
			(size 0.508 2.0574)
			(layers "F.Cu" "F.Mask" "F.Paste")
			(net "GND")
		)
		(pad "6" smd rect
			(at 19.59991 -2.22504 270)
			(size 0.508 2.0574)
			(layers "F.Cu" "F.Mask" "F.Paste")
			(net "GND")
		)
		(pad "7" smd rect
			(at 18.800064 -2.22504 270)
			(size 0.508 2.0574)
			(layers "F.Cu" "F.Mask" "F.Paste")
			(net "P3V3_STBY")
		)
		(pad "8" smd rect
			(at 17.999964 -2.22504 270)
			(size 0.508 2.0574)
			(layers "F.Cu" "F.Mask" "F.Paste")
			(net "GND")
		)
		(pad "9" smd rect
			(at 17.200118 -2.22504 270)
			(size 0.508 2.0574)
			(layers "F.Cu" "F.Mask" "F.Paste")
			(net "GND")
		)
		(pad "10" smd rect
			(at 16.400018 -2.22504 270)
			(size 0.508 2.0574)
			(layers "F.Cu" "F.Mask" "F.Paste")
			(net "P3V3")
		)
		(pad "11" smd rect
			(at 15.599918 -2.22504 270)
			(size 0.508 2.0574)
			(layers "F.Cu" "F.Mask" "F.Paste")
			(net "P3V3")
		)
		(pad "12" smd rect
			(at 14.800072 -2.22504 270)
			(size 0.508 2.0574)
			(layers "F.Cu" "F.Mask" "F.Paste")
			(net "P3V3")
		)
		(pad "13" smd rect
			(at 13.999972 -2.22504 270)
			(size 0.508 2.0574)
			(layers "F.Cu" "F.Mask" "F.Paste")
			(net "P3V3")
		)
		(pad "14" smd rect
			(at 13.200126 -2.22504 270)
			(size 0.508 2.0574)
			(layers "F.Cu" "F.Mask" "F.Paste")
			(net "NCSI_RCSDV_R")
		)
		(pad "15" smd rect
			(at 12.400026 -2.22504 270)
			(size 0.508 2.0574)
			(layers "F.Cu" "F.Mask" "F.Paste")
			(net "NCSI_RCLK")
		)
		(pad "16" smd rect
			(at 11.599926 -2.22504 270)
			(size 0.508 2.0574)
			(layers "F.Cu" "F.Mask" "F.Paste")
			(net "NCSI_TXEN_R")
		)
		(pad "17" smd rect
			(at 10.80008 -2.22504 270)
			(size 0.508 2.0574)
			(layers "F.Cu" "F.Mask" "F.Paste")
			(net "PCIE_COMP_TO_IOM_RST_4_R")
		)
		(pad "18" smd rect
			(at 9.99998 -2.22504 270)
			(size 0.508 2.0574)
			(layers "F.Cu" "F.Mask" "F.Paste")
			(net "I2C_MEZZ_OOB_SCL")
		)
		(pad "19" smd rect
			(at 9.19988 -2.22504 270)
			(size 0.508 2.0574)
			(layers "F.Cu" "F.Mask" "F.Paste")
			(net "I2C_MEZZ_OOB_SDA")
		)
		(pad "20" smd rect
			(at 8.400034 -2.22504 270)
			(size 0.508 2.0574)
			(layers "F.Cu" "F.Mask" "F.Paste")
			(net "GND")
		)
		(pad "21" smd rect
			(at 7.599934 -2.22504 270)
			(size 0.508 2.0574)
			(layers "F.Cu" "F.Mask" "F.Paste")
			(net "GND")
		)
		(pad "22" smd rect
			(at 6.800088 -2.22504 270)
			(size 0.508 2.0574)
			(layers "F.Cu" "F.Mask" "F.Paste")
			(net "NCSI_RXD0_R")
		)
		(pad "23" smd rect
			(at 5.999988 -2.22504 270)
			(size 0.508 2.0574)
			(layers "F.Cu" "F.Mask" "F.Paste")
			(net "NCSI_RXD1_R")
		)
		(pad "24" smd rect
			(at 5.199888 -2.22504 270)
			(size 0.508 2.0574)
			(layers "F.Cu" "F.Mask" "F.Paste")
			(net "GND")
		)
		(pad "25" smd rect
			(at 4.400042 -2.22504 270)
			(size 0.508 2.0574)
			(layers "F.Cu" "F.Mask" "F.Paste")
			(net "GND")
		)
		(pad "26" smd rect
			(at 3.599942 -2.22504 270)
			(size 0.508 2.0574)
			(layers "F.Cu" "F.Mask" "F.Paste")
			(net "Net_31")
		)
		(pad "27" smd rect
			(at 2.800096 -2.22504 270)
			(size 0.508 2.0574)
			(layers "F.Cu" "F.Mask" "F.Paste")
			(net "Net_30")
		)
		(pad "28" smd rect
			(at 1.999996 -2.22504 270)
			(size 0.508 2.0574)
			(layers "F.Cu" "F.Mask" "F.Paste")
			(net "GND")
		)
		(pad "29" smd rect
			(at 1.199896 -2.22504 270)
			(size 0.508 2.0574)
			(layers "F.Cu" "F.Mask" "F.Paste")
			(net "GND")
		)
		(pad "30" smd rect
			(at 0.40005 -2.22504 270)
			(size 0.508 2.0574)
			(layers "F.Cu" "F.Mask" "F.Paste")
			(net "PCIE_IOM_TO_COMP_16_DP")
		)
		(pad "31" smd rect
			(at -0.40005 -2.22504 270)
			(size 0.508 2.0574)
			(layers "F.Cu" "F.Mask" "F.Paste")
			(net "PCIE_IOM_TO_COMP_16_DN")
		)
		(pad "32" smd rect
			(at -1.199896 -2.22504 270)
			(size 0.508 2.0574)
			(layers "F.Cu" "F.Mask" "F.Paste")
			(net "GND")
		)
		(pad "33" smd rect
			(at -1.999996 -2.22504 270)
			(size 0.508 2.0574)
			(layers "F.Cu" "F.Mask" "F.Paste")
			(net "GND")
		)
		(pad "34" smd rect
			(at -2.800096 -2.22504 270)
			(size 0.508 2.0574)
			(layers "F.Cu" "F.Mask" "F.Paste")
			(net "PCIE_IOM_TO_COMP_17_DP")
		)
		(pad "35" smd rect
			(at -3.599942 -2.22504 270)
			(size 0.508 2.0574)
			(layers "F.Cu" "F.Mask" "F.Paste")
			(net "PCIE_IOM_TO_COMP_17_DN")
		)
		(pad "36" smd rect
			(at -4.400042 -2.22504 270)
			(size 0.508 2.0574)
			(layers "F.Cu" "F.Mask" "F.Paste")
			(net "GND")
		)
		(pad "37" smd rect
			(at -5.199888 -2.22504 270)
			(size 0.508 2.0574)
			(layers "F.Cu" "F.Mask" "F.Paste")
			(net "GND")
		)
		(pad "38" smd rect
			(at -5.999988 -2.22504 270)
			(size 0.508 2.0574)
			(layers "F.Cu" "F.Mask" "F.Paste")
			(net "PCIE_IOM_TO_COMP_18_DP")
		)
		(pad "39" smd rect
			(at -6.800088 -2.22504 270)
			(size 0.508 2.0574)
			(layers "F.Cu" "F.Mask" "F.Paste")
			(net "PCIE_IOM_TO_COMP_18_DN")
		)
		(pad "40" smd rect
			(at -7.599934 -2.22504 270)
			(size 0.508 2.0574)
			(layers "F.Cu" "F.Mask" "F.Paste")
			(net "GND")
		)
		(pad "41" smd rect
			(at -8.400034 -2.22504 270)
			(size 0.508 2.0574)
			(layers "F.Cu" "F.Mask" "F.Paste")
			(net "GND")
		)
		(pad "42" smd rect
			(at -9.19988 -2.22504 270)
			(size 0.508 2.0574)
			(layers "F.Cu" "F.Mask" "F.Paste")
			(net "PCIE_IOM_TO_COMP_19_DP")
		)
		(pad "43" smd rect
			(at -9.99998 -2.22504 270)
			(size 0.508 2.0574)
			(layers "F.Cu" "F.Mask" "F.Paste")
			(net "PCIE_IOM_TO_COMP_19_DN")
		)
		(pad "44" smd rect
			(at -10.80008 -2.22504 270)
			(size 0.508 2.0574)
			(layers "F.Cu" "F.Mask" "F.Paste")
			(net "GND")
		)
		(pad "45" smd rect
			(at -11.599926 -2.22504 270)
			(size 0.508 2.0574)
			(layers "F.Cu" "F.Mask" "F.Paste")
			(net "GND")
		)
		(pad "46" smd rect
			(at -12.400026 -2.22504 270)
			(size 0.508 2.0574)
			(layers "F.Cu" "F.Mask" "F.Paste")
			(net "PCIE_IOM_TO_COMP_20_DP")
		)
		(pad "47" smd rect
			(at -13.200126 -2.22504 270)
			(size 0.508 2.0574)
			(layers "F.Cu" "F.Mask" "F.Paste")
			(net "PCIE_IOM_TO_COMP_20_DN")
		)
		(pad "48" smd rect
			(at -13.999972 -2.22504 270)
			(size 0.508 2.0574)
			(layers "F.Cu" "F.Mask" "F.Paste")
			(net "GND")
		)
		(pad "49" smd rect
			(at -14.800072 -2.22504 270)
			(size 0.508 2.0574)
			(layers "F.Cu" "F.Mask" "F.Paste")
			(net "GND")
		)
		(pad "50" smd rect
			(at -15.599918 -2.22504 270)
			(size 0.508 2.0574)
			(layers "F.Cu" "F.Mask" "F.Paste")
			(net "PCIE_IOM_TO_COMP_21_DP")
		)
		(pad "51" smd rect
			(at -16.400018 -2.22504 270)
			(size 0.508 2.0574)
			(layers "F.Cu" "F.Mask" "F.Paste")
			(net "PCIE_IOM_TO_COMP_21_DN")
		)
		(pad "52" smd rect
			(at -17.200118 -2.22504 270)
			(size 0.508 2.0574)
			(layers "F.Cu" "F.Mask" "F.Paste")
			(net "GND")
		)
		(pad "53" smd rect
			(at -17.999964 -2.22504 270)
			(size 0.508 2.0574)
			(layers "F.Cu" "F.Mask" "F.Paste")
			(net "GND")
		)
		(pad "54" smd rect
			(at -18.800064 -2.22504 270)
			(size 0.508 2.0574)
			(layers "F.Cu" "F.Mask" "F.Paste")
			(net "PCIE_IOM_TO_COMP_22_DP")
		)
		(pad "55" smd rect
			(at -19.59991 -2.22504 270)
			(size 0.508 2.0574)
			(layers "F.Cu" "F.Mask" "F.Paste")
			(net "PCIE_IOM_TO_COMP_22_DN")
		)
		(pad "56" smd rect
			(at -20.40001 -2.22504 270)
			(size 0.508 2.0574)
			(layers "F.Cu" "F.Mask" "F.Paste")
			(net "GND")
		)
		(pad "57" smd rect
			(at -21.20011 -2.22504 270)
			(size 0.508 2.0574)
			(layers "F.Cu" "F.Mask" "F.Paste")
			(net "GND")
		)
		(pad "58" smd rect
			(at -21.999956 -2.22504 270)
			(size 0.508 2.0574)
			(layers "F.Cu" "F.Mask" "F.Paste")
			(net "PCIE_IOM_TO_COMP_23_DP")
		)
		(pad "59" smd rect
			(at -22.800056 -2.22504 270)
			(size 0.508 2.0574)
			(layers "F.Cu" "F.Mask" "F.Paste")
			(net "PCIE_IOM_TO_COMP_23_DN")
		)
		(pad "60" smd rect
			(at -23.599902 -2.22504 270)
			(size 0.508 2.0574)
			(layers "F.Cu" "F.Mask" "F.Paste")
			(net "GND")
		)
		(pad "61" smd rect
			(at 23.599902 2.22504 270)
			(size 0.508 2.0574)
			(layers "F.Cu" "F.Mask" "F.Paste")
			(net "P12V_STBY")
		)
		(pad "62" smd rect
			(at 22.800056 2.22504 270)
			(size 0.508 2.0574)
			(layers "F.Cu" "F.Mask" "F.Paste")
			(net "P12V_STBY")
		)
		(pad "63" smd rect
			(at 21.999956 2.22504 270)
			(size 0.508 2.0574)
			(layers "F.Cu" "F.Mask" "F.Paste")
			(net "P12V_STBY")
		)
		(pad "64" smd rect
			(at 21.20011 2.22504 270)
			(size 0.508 2.0574)
			(layers "F.Cu" "F.Mask" "F.Paste")
			(net "GND")
		)
		(pad "65" smd rect
			(at 20.40001 2.22504 270)
			(size 0.508 2.0574)
			(layers "F.Cu" "F.Mask" "F.Paste")
			(net "GND")
		)
		(pad "66" smd rect
			(at 19.59991 2.22504 270)
			(size 0.508 2.0574)
			(layers "F.Cu" "F.Mask" "F.Paste")
			(net "P3V3_STBY")
		)
		(pad "67" smd rect
			(at 18.800064 2.22504 270)
			(size 0.508 2.0574)
			(layers "F.Cu" "F.Mask" "F.Paste")
			(net "GND")
		)
		(pad "68" smd rect
			(at 17.999964 2.22504 270)
			(size 0.508 2.0574)
			(layers "F.Cu" "F.Mask" "F.Paste")
			(net "GND")
		)
		(pad "69" smd rect
			(at 17.200118 2.22504 270)
			(size 0.508 2.0574)
			(layers "F.Cu" "F.Mask" "F.Paste")
			(net "P3V3")
		)
		(pad "70" smd rect
			(at 16.400018 2.22504 270)
			(size 0.508 2.0574)
			(layers "F.Cu" "F.Mask" "F.Paste")
			(net "P3V3")
		)
		(pad "71" smd rect
			(at 15.599918 2.22504 270)
			(size 0.508 2.0574)
			(layers "F.Cu" "F.Mask" "F.Paste")
			(net "P3V3")
		)
		(pad "72" smd rect
			(at 14.800072 2.22504 270)
			(size 0.508 2.0574)
			(layers "F.Cu" "F.Mask" "F.Paste")
			(net "P3V3")
		)
		(pad "73" smd rect
			(at 13.999972 2.22504 270)
			(size 0.508 2.0574)
			(layers "F.Cu" "F.Mask" "F.Paste")
			(net "GND")
		)
		(pad "74" smd rect
			(at 13.200126 2.22504 270)
			(size 0.508 2.0574)
			(layers "F.Cu" "F.Mask" "F.Paste")
			(net "I2C_MEZZ_ALERT_R_N")
		)
		(pad "75" smd rect
			(at 12.400026 2.22504 270)
			(size 0.508 2.0574)
			(layers "F.Cu" "F.Mask" "F.Paste")
			(net "I2C_MEZZ_FRU_SENSOR_SCL")
		)
		(pad "76" smd rect
			(at 11.599926 2.22504 270)
			(size 0.508 2.0574)
			(layers "F.Cu" "F.Mask" "F.Paste")
			(net "I2C_MEZZ_FRU_SENSOR_SDA")
		)
		(pad "77" smd rect
			(at 10.80008 2.22504 270)
			(size 0.508 2.0574)
			(layers "F.Cu" "F.Mask" "F.Paste")
			(net "PCIE_WAKE_N")
		)
		(pad "78" smd rect
			(at 9.99998 2.22504 270)
			(size 0.508 2.0574)
			(layers "F.Cu" "F.Mask" "F.Paste")
			(net "NCSI_RX_ER_R")
		)
		(pad "79" smd rect
			(at 9.19988 2.22504 270)
			(size 0.508 2.0574)
			(layers "F.Cu" "F.Mask" "F.Paste")
			(net "GND")
		)
		(pad "80" smd rect
			(at 8.400034 2.22504 270)
			(size 0.508 2.0574)
			(layers "F.Cu" "F.Mask" "F.Paste")
			(net "NCSI_TXD0")
		)
		(pad "81" smd rect
			(at 7.599934 2.22504 270)
			(size 0.508 2.0574)
			(layers "F.Cu" "F.Mask" "F.Paste")
			(net "NCSI_TXD1")
		)
		(pad "82" smd rect
			(at 6.800088 2.22504 270)
			(size 0.508 2.0574)
			(layers "F.Cu" "F.Mask" "F.Paste")
			(net "GND")
		)
		(pad "83" smd rect
			(at 5.999988 2.22504 270)
			(size 0.508 2.0574)
			(layers "F.Cu" "F.Mask" "F.Paste")
			(net "GND")
		)
		(pad "84" smd rect
			(at 5.199888 2.22504 270)
			(size 0.508 2.0574)
			(layers "F.Cu" "F.Mask" "F.Paste")
			(net "PCIE_COMP_TO_IOM_CLK_4_DP")
		)
		(pad "85" smd rect
			(at 4.400042 2.22504 270)
			(size 0.508 2.0574)
			(layers "F.Cu" "F.Mask" "F.Paste")
			(net "PCIE_COMP_TO_IOM_CLK_4_DN")
		)
		(pad "86" smd rect
			(at 3.599942 2.22504 270)
			(size 0.508 2.0574)
			(layers "F.Cu" "F.Mask" "F.Paste")
			(net "GND")
		)
		(pad "87" smd rect
			(at 2.800096 2.22504 270)
			(size 0.508 2.0574)
			(layers "F.Cu" "F.Mask" "F.Paste")
			(net "GND")
		)
		(pad "88" smd rect
			(at 1.999996 2.22504 270)
			(size 0.508 2.0574)
			(layers "F.Cu" "F.Mask" "F.Paste")
			(net "PCIE_COMP_TO_IOM_16_DP")
		)
		(pad "89" smd rect
			(at 1.199896 2.22504 270)
			(size 0.508 2.0574)
			(layers "F.Cu" "F.Mask" "F.Paste")
			(net "PCIE_COMP_TO_IOM_16_DN")
		)
		(pad "90" smd rect
			(at 0.40005 2.22504 270)
			(size 0.508 2.0574)
			(layers "F.Cu" "F.Mask" "F.Paste")
			(net "GND")
		)
		(pad "91" smd rect
			(at -0.40005 2.22504 270)
			(size 0.508 2.0574)
			(layers "F.Cu" "F.Mask" "F.Paste")
			(net "GND")
		)
		(pad "92" smd rect
			(at -1.199896 2.22504 270)
			(size 0.508 2.0574)
			(layers "F.Cu" "F.Mask" "F.Paste")
			(net "PCIE_COMP_TO_IOM_17_DP")
		)
		(pad "93" smd rect
			(at -1.999996 2.22504 270)
			(size 0.508 2.0574)
			(layers "F.Cu" "F.Mask" "F.Paste")
			(net "PCIE_COMP_TO_IOM_17_DN")
		)
		(pad "94" smd rect
			(at -2.800096 2.22504 270)
			(size 0.508 2.0574)
			(layers "F.Cu" "F.Mask" "F.Paste")
			(net "GND")
		)
		(pad "95" smd rect
			(at -3.599942 2.22504 270)
			(size 0.508 2.0574)
			(layers "F.Cu" "F.Mask" "F.Paste")
			(net "GND")
		)
		(pad "96" smd rect
			(at -4.400042 2.22504 270)
			(size 0.508 2.0574)
			(layers "F.Cu" "F.Mask" "F.Paste")
			(net "PCIE_COMP_TO_IOM_18_DP")
		)
		(pad "97" smd rect
			(at -5.199888 2.22504 270)
			(size 0.508 2.0574)
			(layers "F.Cu" "F.Mask" "F.Paste")
			(net "PCIE_COMP_TO_IOM_18_DN")
		)
		(pad "98" smd rect
			(at -5.999988 2.22504 270)
			(size 0.508 2.0574)
			(layers "F.Cu" "F.Mask" "F.Paste")
			(net "GND")
		)
		(pad "99" smd rect
			(at -6.800088 2.22504 270)
			(size 0.508 2.0574)
			(layers "F.Cu" "F.Mask" "F.Paste")
			(net "GND")
		)
		(pad "100" smd rect
			(at -7.599934 2.22504 270)
			(size 0.508 2.0574)
			(layers "F.Cu" "F.Mask" "F.Paste")
			(net "PCIE_COMP_TO_IOM_19_DP")
		)
		(pad "101" smd rect
			(at -8.400034 2.22504 270)
			(size 0.508 2.0574)
			(layers "F.Cu" "F.Mask" "F.Paste")
			(net "PCIE_COMP_TO_IOM_19_DN")
		)
		(pad "102" smd rect
			(at -9.19988 2.22504 270)
			(size 0.508 2.0574)
			(layers "F.Cu" "F.Mask" "F.Paste")
			(net "GND")
		)
		(pad "103" smd rect
			(at -9.99998 2.22504 270)
			(size 0.508 2.0574)
			(layers "F.Cu" "F.Mask" "F.Paste")
			(net "GND")
		)
		(pad "104" smd rect
			(at -10.80008 2.22504 270)
			(size 0.508 2.0574)
			(layers "F.Cu" "F.Mask" "F.Paste")
			(net "PCIE_COMP_TO_IOM_20_DP")
		)
		(pad "105" smd rect
			(at -11.599926 2.22504 270)
			(size 0.508 2.0574)
			(layers "F.Cu" "F.Mask" "F.Paste")
			(net "PCIE_COMP_TO_IOM_20_DN")
		)
		(pad "106" smd rect
			(at -12.400026 2.22504 270)
			(size 0.508 2.0574)
			(layers "F.Cu" "F.Mask" "F.Paste")
			(net "GND")
		)
		(pad "107" smd rect
			(at -13.200126 2.22504 270)
			(size 0.508 2.0574)
			(layers "F.Cu" "F.Mask" "F.Paste")
			(net "GND")
		)
		(pad "108" smd rect
			(at -13.999972 2.22504 270)
			(size 0.508 2.0574)
			(layers "F.Cu" "F.Mask" "F.Paste")
			(net "PCIE_COMP_TO_IOM_21_DP")
		)
		(pad "109" smd rect
			(at -14.800072 2.22504 270)
			(size 0.508 2.0574)
			(layers "F.Cu" "F.Mask" "F.Paste")
			(net "PCIE_COMP_TO_IOM_21_DN")
		)
		(pad "110" smd rect
			(at -15.599918 2.22504 270)
			(size 0.508 2.0574)
			(layers "F.Cu" "F.Mask" "F.Paste")
			(net "GND")
		)
		(pad "111" smd rect
			(at -16.400018 2.22504 270)
			(size 0.508 2.0574)
			(layers "F.Cu" "F.Mask" "F.Paste")
			(net "GND")
		)
		(pad "112" smd rect
			(at -17.200118 2.22504 270)
			(size 0.508 2.0574)
			(layers "F.Cu" "F.Mask" "F.Paste")
			(net "PCIE_COMP_TO_IOM_22_DP")
		)
		(pad "113" smd rect
			(at -17.999964 2.22504 270)
			(size 0.508 2.0574)
			(layers "F.Cu" "F.Mask" "F.Paste")
			(net "PCIE_COMP_TO_IOM_22_DN")
		)
		(pad "114" smd rect
			(at -18.800064 2.22504 270)
			(size 0.508 2.0574)
			(layers "F.Cu" "F.Mask" "F.Paste")
			(net "GND")
		)
		(pad "115" smd rect
			(at -19.59991 2.22504 270)
			(size 0.508 2.0574)
			(layers "F.Cu" "F.Mask" "F.Paste")
			(net "GND")
		)
	)
)
